# T6G (Grand Teton) — schematic netlist excerpt (pin names and nets, part order shuffled) for the footprints in the layout excerpt that follows; sources: Cadence DE-HDL packaged netlist, KiCad conversion of 04192023_DAF0TMB3IC0_F0TG_MB_C_brd_V02_OCP.brd

R3232  Q_RES  100K 1% CHIP  pkg 0402LF  page 132 : A = RST_HP_OCP_SFF_R_N ; B = GND
PL6001  Q_INDUCTOR  2.2UH IND  pkg SMLF  page 270 : \1\ = SW_P1V2_AUX_PH ; \2\ = P1V2_AUX

(kicad_pcb
	(version 20260206)
	(generator "pcbnew")
	(generator_version "10.0")
	(general
		(thickness 1.6)
		(legacy_teardrops no)
	)
	(paper "A4")
	(title_block
		(title "04192023_DAF0TMB3IC0_F0TG_MB_C_brd_V02_OCP.brd")
		(comment 1 "Grand Teton / footprints 1279-1281 of 8354")
	)
	(layers
		(0 "F.Cu" signal "TOP")
		(4 "In1.Cu" signal "GND")
		(6 "In2.Cu" signal "IN1")
		(8 "In3.Cu" signal "GND1")
		(10 "In4.Cu" signal "IN2")
		(12 "In5.Cu" signal "GND2")
		(14 "In6.Cu" signal "IN3")
		(16 "In7.Cu" signal "GND3")
		(18 "In8.Cu" signal "VCC")
		(20 "In9.Cu" signal "VCC1")
		(22 "In10.Cu" signal "GND4")
		(24 "In11.Cu" signal "IN4")
		(26 "In12.Cu" signal "GND5")
		(28 "In13.Cu" signal "IN5")
		(30 "In14.Cu" signal "GND6")
		(32 "In15.Cu" signal "IN6")
		(34 "In16.Cu" signal "GND7")
		(2 "B.Cu" signal "BOTTOM")
		(9 "F.Adhes" user "F.Adhesive")
		(11 "B.Adhes" user "B.Adhesive")
		(13 "F.Paste" user "Package Geometry/Pastemask Top")
		(15 "B.Paste" user "Package Geometry/Pastemask Bottom")
		(5 "F.SilkS" user "Ref Des/Silkscreen Top")
		(7 "B.SilkS" user "Ref Des/Silkscreen Bottom")
		(1 "F.Mask" user "Board Geometry/Soldermask Top")
		(3 "B.Mask" user "Board Geometry/Soldermask Bottom")
		(17 "Dwgs.User" user "User.Drawings")
		(19 "Cmts.User" user "User.Comments")
		(21 "Eco1.User" user "User.Eco1")
		(23 "Eco2.User" user "User.Eco2")
		(25 "Edge.Cuts" user "Board Geometry/Outline")
		(27 "Margin" user)
		(31 "F.CrtYd" user "Package Geometry/Place Bound Top")
		(29 "B.CrtYd" user "Package Geometry/Place Bound Bottom")
		(35 "F.Fab" user "Ref Des/Assembly Top")
		(33 "B.Fab" user "Ref Des/Assembly Bottom")
	)
	(footprint ""
		(layer "F.Cu")
		(at 463.735928 -93.309186)
		(property "Reference" "R3232"
			(at 0 0 0)
			(layer "F.SilkS")
			(hide yes)
			(effects
				(font
					(size 1.27 1.27)
				)
			)
		)
		(property "Value" ""
			(at 0 0 0)
			(layer "F.Fab")
			(effects
				(font
					(size 1.27 1.27)
				)
			)
		)
		(duplicate_pad_numbers_are_jumpers no)
		(fp_line
			(start -0.7874 -0.4064)
			(end 0.7874 -0.4064)
			(stroke
				(width 0.1524)
				(type default)
			)
			(layer "F.SilkS")
		)
		(fp_line
			(start -0.7874 0.4064)
			(end -0.7874 -0.4064)
			(stroke
				(width 0.1524)
				(type default)
			)
			(layer "F.SilkS")
		)
		(fp_line
			(start 0.7874 -0.4064)
			(end 0.7874 0.4064)
			(stroke
				(width 0.1524)
				(type default)
			)
			(layer "F.SilkS")
		)
		(fp_line
			(start 0.7874 0.4064)
			(end -0.7874 0.4064)
			(stroke
				(width 0.1524)
				(type default)
			)
			(layer "F.SilkS")
		)
		(fp_line
			(start -0.67945 -0.305054)
			(end -0.12065 -0.305054)
			(stroke
				(width 0.1)
				(type default)
			)
			(layer "F.Fab")
		)
		(fp_line
			(start -0.67945 0.3048)
			(end -0.67945 -0.305054)
			(stroke
				(width 0.1)
				(type default)
			)
			(layer "F.Fab")
		)
		(fp_line
			(start -0.12065 -0.305054)
			(end -0.12065 -0.2794)
			(stroke
				(width 0.1)
				(type default)
			)
			(layer "F.Fab")
		)
		(fp_line
			(start -0.12065 -0.2794)
			(end 0.12065 -0.2794)
			(stroke
				(width 0.1)
				(type default)
			)
			(layer "F.Fab")
		)
		(fp_line
			(start -0.12065 0.2794)
			(end -0.12065 0.3048)
			(stroke
				(width 0.1)
				(type default)
			)
			(layer "F.Fab")
		)
		(fp_line
			(start -0.12065 0.3048)
			(end -0.67945 0.3048)
			(stroke
				(width 0.1)
				(type default)
			)
			(layer "F.Fab")
		)
		(fp_line
			(start 0.120396 0.2794)
			(end -0.12065 0.2794)
			(stroke
				(width 0.1)
				(type default)
			)
			(layer "F.Fab")
		)
		(fp_line
			(start 0.120396 0.3048)
			(end 0.120396 0.2794)
			(stroke
				(width 0.1)
				(type default)
			)
			(layer "F.Fab")
		)
		(fp_line
			(start 0.12065 -0.3048)
			(end 0.67945 -0.3048)
			(stroke
				(width 0.1)
				(type default)
			)
			(layer "F.Fab")
		)
		(fp_line
			(start 0.12065 -0.2794)
			(end 0.12065 -0.3048)
			(stroke
				(width 0.1)
				(type default)
			)
			(layer "F.Fab")
		)
		(fp_line
			(start 0.67945 -0.3048)
			(end 0.67945 0.3048)
			(stroke
				(width 0.1)
				(type default)
			)
			(layer "F.Fab")
		)
		(fp_line
			(start 0.67945 0.3048)
			(end 0.120396 0.3048)
			(stroke
				(width 0.1)
				(type default)
			)
			(layer "F.Fab")
		)
		(pad "1" smd circle
			(at -0.40005 0)
			(size 0 0)
			(layers "F.Cu" "F.Mask" "F.Paste")
			(net "RST_HP_OCP_SFF_R_N")
		)
		(pad "2" smd circle
			(at 0.40005 0)
			(size 0 0)
			(layers "F.Cu" "F.Mask" "F.Paste")
			(net "GND")
		)
	)
	(footprint ""
		(layer "F.Cu")
		(at 129.084832 -75.466956)
		(property "Reference" "PL6001"
			(at -5.210048 -5.253482 0)
			(unlocked yes)
			(layer "F.SilkS")
			(effects
				(font
					(size 0.7874 0.5842)
					(thickness 0.1524)
				)
				(justify left)
			)
		)
		(property "Value" ""
			(at 0 0 0)
			(layer "F.Fab")
			(effects
				(font
					(size 1.27 1.27)
				)
			)
		)
		(duplicate_pad_numbers_are_jumpers no)
		(fp_line
			(start -3.6576 -3.350006)
			(end 3.64998 -3.350006)
			(stroke
				(width 0.1524)
				(type default)
			)
			(layer "F.SilkS")
		)
		(fp_line
			(start -3.64998 -1.8034)
			(end -3.64998 -3.350006)
			(stroke
				(width 0.1524)
				(type default)
			)
			(layer "F.SilkS")
		)
		(fp_line
			(start -3.64998 3.350006)
			(end -3.64998 1.8288)
			(stroke
				(width 0.1524)
				(type default)
			)
			(layer "F.SilkS")
		)
		(fp_line
			(start 3.64998 -3.350006)
			(end 3.64998 -1.8034)
			(stroke
				(width 0.1524)
				(type default)
			)
			(layer "F.SilkS")
		)
		(fp_line
			(start 3.64998 1.8034)
			(end 3.64998 3.350006)
			(stroke
				(width 0.1524)
				(type default)
			)
			(layer "F.SilkS")
		)
		(fp_line
			(start 3.64998 3.350006)
			(end -3.64998 3.350006)
			(stroke
				(width 0.1524)
				(type default)
			)
			(layer "F.SilkS")
		)
		(fp_line
			(start -3.64998 -3.350006)
			(end 3.64998 -3.350006)
			(stroke
				(width 0.1)
				(type default)
			)
			(layer "F.Fab")
		)
		(fp_line
			(start -3.64998 3.350006)
			(end -3.64998 -3.350006)
			(stroke
				(width 0.1)
				(type default)
			)
			(layer "F.Fab")
		)
		(fp_line
			(start 3.64998 -3.350006)
			(end 3.64998 3.350006)
			(stroke
				(width 0.1)
				(type default)
			)
			(layer "F.Fab")
		)
		(fp_line
			(start 3.64998 3.350006)
			(end -3.64998 3.350006)
			(stroke
				(width 0.1)
				(type default)
			)
			(layer "F.Fab")
		)
		(pad "1" smd rect
			(at -2.92481 0)
			(size 2.15392 3.302)
			(layers "F.Cu" "F.Mask" "F.Paste")
			(net "SW_P1V2_AUX_PH")
		)
		(pad "2" smd rect
			(at 2.92481 0)
			(size 2.15392 3.302)
			(layers "F.Cu" "F.Mask" "F.Paste")
			(net "P1V2_AUX")
		)
	)
	(footprint ""
		(layer "F.Cu")
		(at 378.449078 -356.362508 180)
		(property "Reference" ""
			(at 0 0 180)
			(layer "F.SilkS")
			(hide yes)
			(effects
				(font
					(size 1.27 1.27)
				)
			)
		)
		(property "Value" ""
			(at 0 0 180)
			(layer "F.Fab")
			(effects
				(font
					(size 1.27 1.27)
				)
			)
		)
		(duplicate_pad_numbers_are_jumpers no)
		(pad "1" smd circle
			(at 0 0 180)
			(size 0.9906 0.9906)
			(layers "F.Cu" "F.Mask" "F.Paste")
			(net "Net_47")
		)
		(zone
			(layer "F.Cu")
			(hatch none 0.5)
			(connect_pads
				(clearance 0)
			)
			(min_thickness 0.25)
			(keepout
				(tracks not_allowed)
				(vias allowed)
				(pads allowed)
				(copperpour not_allowed)
				(footprints allowed)
			)
			(placement
				(enabled no)
				(sheetname "")
			)
			(fill
				(thermal_gap 0.5)
				(thermal_bridge_width 0.5)
				(island_removal_mode 0)
			)
			(polygon
				(pts
					(arc
						(start 380.074678 -356.362508)
						(mid 376.823478 -356.362508)
						(end 380.074678 -356.362508)
					)
				)
			)
		)
	)
)
